(kicad_pcb
	(version 20241229)
	(generator "pcbnew")
	(generator_version "9.0")
	(general
		(thickness 1.711)
		(legacy_teardrops no)
	)
	(paper "A4")
	(title_block
		(title "Antmicro Baseboard for Jetson AGX Thor")
		(date "2026-02-18")
		(rev "1.1.0")
		(company "Antmicro Ltd")
		(comment 1 "www.antmicro.com")
		(comment 9 "footprints 857-862 of 1170")
	)
	(layers
		(0 "F.Cu" signal)
		(4 "In1.Cu" signal)
		(6 "In2.Cu" signal)
		(8 "In3.Cu" signal)
		(10 "In4.Cu" jumper)
		(12 "In5.Cu" signal)
		(14 "In6.Cu" signal)
		(16 "In7.Cu" signal)
		(18 "In8.Cu" signal)
		(2 "B.Cu" signal)
		(9 "F.Adhes" user "F.Adhesive")
		(11 "B.Adhes" user "B.Adhesive")
		(13 "F.Paste" user)
		(15 "B.Paste" user)
		(5 "F.SilkS" user "F.Silkscreen")
		(7 "B.SilkS" user "B.Silkscreen")
		(1 "F.Mask" user)
		(3 "B.Mask" user)
		(17 "Dwgs.User" user "User.Drawings")
		(19 "Cmts.User" user "User.Comments")
		(21 "Eco1.User" user "User.Eco1")
		(23 "Eco2.User" user "User.Eco2")
		(25 "Edge.Cuts" user)
		(27 "Margin" user)
		(31 "F.CrtYd" user "F.Courtyard")
		(29 "B.CrtYd" user "B.Courtyard")
		(35 "F.Fab" user)
		(33 "B.Fab" user)
	)
	(footprint "antmicro-footprints:TP_SMD_0.75mm"
		(layer "B.Cu")
		(at 234 71.5 90)
		(property "Reference" "TP83"
			(at -1.1 -1.6 90)
			(layer "B.SilkS")
			(effects
				(font
					(size 0.7 0.7)
					(thickness 0.15)
				)
				(justify right top mirror)
			)
		)
		(property "Value" "TP_0.75mm_SMD"
			(at 0 -1.2 90)
			(layer "B.Fab")
			(effects
				(font
					(size 0.7 0.7)
					(thickness 0.15)
				)
				(justify right top mirror)
			)
		)
		(property "Description" "SMT test point"
			(at 0 0 90)
			(layer "B.Fab")
			(hide yes)
			(effects
				(font
					(size 1.27 1.27)
					(thickness 0.15)
				)
				(justify mirror)
			)
		)
		(property "MPN" ""
			(at 0 0 270)
			(unlocked yes)
			(layer "B.Fab")
			(hide yes)
			(effects
				(font
					(size 1 1)
					(thickness 0.15)
				)
				(justify mirror)
			)
		)
		(property "Manufacturer" ""
			(at 0 0 270)
			(unlocked yes)
			(layer "B.Fab")
			(hide yes)
			(effects
				(font
					(size 1 1)
					(thickness 0.15)
				)
				(justify mirror)
			)
		)
		(property "Author" "Antmicro"
			(at 0 0 270)
			(unlocked yes)
			(layer "B.Fab")
			(hide yes)
			(effects
				(font
					(size 1 1)
					(thickness 0.15)
				)
				(justify mirror)
			)
		)
		(property "License" "Apache-2.0"
			(at 0 0 270)
			(unlocked yes)
			(layer "B.Fab")
			(hide yes)
			(effects
				(font
					(size 1 1)
					(thickness 0.15)
				)
				(justify mirror)
			)
		)
		(sheetname "/SoM_Power/")
		(sheetfile "som_power.kicad_sch")
		(attr exclude_from_pos_files exclude_from_bom)
		(fp_circle
			(center 0 0)
			(end 0.475 0)
			(stroke
				(width 0.05)
				(type default)
			)
			(fill no)
			(layer "B.CrtYd")
		)
		(fp_text user "License: Apache-2.0"
			(at -0.4 -5.101 90)
			(layer "B.Fab")
			(effects
				(font
					(size 0.7 0.7)
					(thickness 0.15)
				)
				(justify right top mirror)
			)
		)
		(fp_text user "${REFERENCE}"
			(at -0.4 -2.7 90)
			(layer "B.Fab")
			(effects
				(font
					(size 0.7 0.7)
					(thickness 0.15)
				)
				(justify right top mirror)
			)
		)
		(fp_text user "Author: Antmicro"
			(at -0.4 -3.901 90)
			(layer "B.Fab")
			(effects
				(font
					(size 0.7 0.7)
					(thickness 0.15)
				)
				(justify right top mirror)
			)
		)
		(pad "1" smd circle
			(at 0 0 90)
			(size 0.75 0.75)
			(layers "B.Cu" "B.Mask")
			(net 702 "/SoM_Power/~{SYS_RESET}")
			(pinfunction "1")
			(pintype "passive")
		)
	)
	(footprint "antmicro-footprints:TP_SMD_0.75mm"
		(layer "B.Cu")
		(at 140.330532 71.31 90)
		(property "Reference" "TP48"
			(at -3.26 0.069468 90)
			(layer "B.SilkS")
			(effects
				(font
					(size 0.7 0.7)
					(thickness 0.15)
				)
				(justify right top mirror)
			)
		)
		(property "Value" "TP_0.75mm_SMD"
			(at 0 -1.2 90)
			(layer "B.Fab")
			(effects
				(font
					(size 0.7 0.7)
					(thickness 0.15)
				)
				(justify right top mirror)
			)
		)
		(property "Description" "SMT test point"
			(at 0 0 90)
			(layer "B.Fab")
			(hide yes)
			(effects
				(font
					(size 1.27 1.27)
					(thickness 0.15)
				)
				(justify mirror)
			)
		)
		(property "MPN" ""
			(at 0 0 270)
			(unlocked yes)
			(layer "B.Fab")
			(hide yes)
			(effects
				(font
					(size 1 1)
					(thickness 0.15)
				)
				(justify mirror)
			)
		)
		(property "Manufacturer" ""
			(at 0 0 270)
			(unlocked yes)
			(layer "B.Fab")
			(hide yes)
			(effects
				(font
					(size 1 1)
					(thickness 0.15)
				)
				(justify mirror)
			)
		)
		(property "Author" "Antmicro"
			(at 0 0 270)
			(unlocked yes)
			(layer "B.Fab")
			(hide yes)
			(effects
				(font
					(size 1 1)
					(thickness 0.15)
				)
				(justify mirror)
			)
		)
		(property "License" "Apache-2.0"
			(at 0 0 270)
			(unlocked yes)
			(layer "B.Fab")
			(hide yes)
			(effects
				(font
					(size 1 1)
					(thickness 0.15)
				)
				(justify mirror)
			)
		)
		(sheetname "/SoM_Power/")
		(sheetfile "som_power.kicad_sch")
		(attr exclude_from_pos_files exclude_from_bom)
		(fp_circle
			(center 0 0)
			(end 0.475 0)
			(stroke
				(width 0.05)
				(type default)
			)
			(fill no)
			(layer "B.CrtYd")
		)
		(fp_text user "License: Apache-2.0"
			(at -0.4 -5.101 90)
			(layer "B.Fab")
			(effects
				(font
					(size 0.7 0.7)
					(thickness 0.15)
				)
				(justify right top mirror)
			)
		)
		(fp_text user "${REFERENCE}"
			(at -0.4 -2.7 90)
			(layer "B.Fab")
			(effects
				(font
					(size 0.7 0.7)
					(thickness 0.15)
				)
				(justify right top mirror)
			)
		)
		(fp_text user "Author: Antmicro"
			(at -0.4 -3.901 90)
			(layer "B.Fab")
			(effects
				(font
					(size 0.7 0.7)
					(thickness 0.15)
				)
				(justify right top mirror)
			)
		)
		(pad "1" smd circle
			(at 0 0 90)
			(size 0.75 0.75)
			(layers "B.Cu" "B.Mask")
			(net 741 "Net-(J1A-PERIPHERAL_RESET_N)")
			(pinfunction "1")
			(pintype "passive")
		)
	)
	(footprint "antmicro-footprints:TP_SMD_0.75mm"
		(layer "B.Cu")
		(at 139.030532 71.31 90)
		(property "Reference" "TP50"
			(at -3.26 0.458936 90)
			(layer "B.SilkS")
			(effects
				(font
					(size 0.7 0.7)
					(thickness 0.15)
				)
				(justify right top mirror)
			)
		)
		(property "Value" "TP_0.75mm_SMD"
			(at 0 -1.2 90)
			(layer "B.Fab")
			(effects
				(font
					(size 0.7 0.7)
					(thickness 0.15)
				)
				(justify right top mirror)
			)
		)
		(property "Description" "SMT test point"
			(at 0 0 90)
			(layer "B.Fab")
			(hide yes)
			(effects
				(font
					(size 1.27 1.27)
					(thickness 0.15)
				)
				(justify mirror)
			)
		)
		(property "MPN" ""
			(at 0 0 270)
			(unlocked yes)
			(layer "B.Fab")
			(hide yes)
			(effects
				(font
					(size 1 1)
					(thickness 0.15)
				)
				(justify mirror)
			)
		)
		(property "Manufacturer" ""
			(at 0 0 270)
			(unlocked yes)
			(layer "B.Fab")
			(hide yes)
			(effects
				(font
					(size 1 1)
					(thickness 0.15)
				)
				(justify mirror)
			)
		)
		(property "Author" "Antmicro"
			(at 0 0 270)
			(unlocked yes)
			(layer "B.Fab")
			(hide yes)
			(effects
				(font
					(size 1 1)
					(thickness 0.15)
				)
				(justify mirror)
			)
		)
		(property "License" "Apache-2.0"
			(at 0 0 270)
			(unlocked yes)
			(layer "B.Fab")
			(hide yes)
			(effects
				(font
					(size 1 1)
					(thickness 0.15)
				)
				(justify mirror)
			)
		)
		(sheetname "/SoM_Power/")
		(sheetfile "som_power.kicad_sch")
		(attr exclude_from_pos_files exclude_from_bom)
		(fp_circle
			(center 0 0)
			(end 0.475 0)
			(stroke
				(width 0.05)
				(type default)
			)
			(fill no)
			(layer "B.CrtYd")
		)
		(fp_text user "${REFERENCE}"
			(at -0.4 -2.7 90)
			(layer "B.Fab")
			(effects
				(font
					(size 0.7 0.7)
					(thickness 0.15)
				)
				(justify right top mirror)
			)
		)
		(fp_text user "Author: Antmicro"
			(at -0.4 -3.901 90)
			(layer "B.Fab")
			(effects
				(font
					(size 0.7 0.7)
					(thickness 0.15)
				)
				(justify right top mirror)
			)
		)
		(fp_text user "License: Apache-2.0"
			(at -0.4 -5.101 90)
			(layer "B.Fab")
			(effects
				(font
					(size 0.7 0.7)
					(thickness 0.15)
				)
				(justify right top mirror)
			)
		)
		(pad "1" smd circle
			(at 0 0 90)
			(size 0.75 0.75)
			(layers "B.Cu" "B.Mask")
			(net 621 "Net-(J1A-THERM_ALERT_N)")
			(pinfunction "1")
			(pintype "passive")
		)
	)
	(footprint "antmicro-footprints:SOD-523"
		(layer "B.Cu")
		(at 218.84 123.931698 90)
		(property "Reference" "D60"
			(at -1.068302 -1.54 90)
			(layer "B.SilkS")
			(effects
				(font
					(size 0.7 0.7)
					(thickness 0.15)
				)
				(justify right top mirror)
			)
		)
		(property "Value" "RB521S30T1G"
			(at 0 -1.499 90)
			(layer "B.Fab")
			(effects
				(font
					(size 0.7 0.7)
					(thickness 0.15)
				)
				(justify right top mirror)
			)
		)
		(property "Datasheet" "https://www.onsemi.com/pdf/datasheet/rb521s30t1-d.pdf"
			(at 0 0 90)
			(layer "B.Fab")
			(hide yes)
			(effects
				(font
					(size 1.27 1.27)
					(thickness 0.15)
				)
				(justify mirror)
			)
		)
		(property "Description" "Small Signal Schottky Diode, Single, 30 V, 200 mA, 500 mV, 1 A, 125 °C"
			(at 0 0 90)
			(layer "B.Fab")
			(hide yes)
			(effects
				(font
					(size 1.27 1.27)
					(thickness 0.15)
				)
				(justify mirror)
			)
		)
		(property "MPN" "RB521S30T1G"
			(at 0 0 270)
			(unlocked yes)
			(layer "B.Fab")
			(hide yes)
			(effects
				(font
					(size 1 1)
					(thickness 0.15)
				)
				(justify mirror)
			)
		)
		(property "Manufacturer" "ON Semiconductor"
			(at 0 0 270)
			(unlocked yes)
			(layer "B.Fab")
			(hide yes)
			(effects
				(font
					(size 1 1)
					(thickness 0.15)
				)
				(justify mirror)
			)
		)
		(property "Author" "Antmicro"
			(at 0 0 270)
			(unlocked yes)
			(layer "B.Fab")
			(hide yes)
			(effects
				(font
					(size 1 1)
					(thickness 0.15)
				)
				(justify mirror)
			)
		)
		(property "License" "Apache-2.0"
			(at 0 0 270)
			(unlocked yes)
			(layer "B.Fab")
			(hide yes)
			(effects
				(font
					(size 1 1)
					(thickness 0.15)
				)
				(justify mirror)
			)
		)
		(sheetname "/USB Hub/")
		(sheetfile "usb_hub.kicad_sch")
		(attr smd)
		(fp_line
			(start -0.35 0.5)
			(end -0.35 -0.5)
			(stroke
				(width 0.15)
				(type solid)
			)
			(layer "B.SilkS")
		)
		(fp_rect
			(start -1 0.6)
			(end 1 -0.6)
			(stroke
				(width 0.05)
				(type solid)
			)
			(fill no)
			(layer "B.CrtYd")
		)
		(fp_line
			(start -0.652 -0.423)
			(end 0.65 -0.423)
			(stroke
				(width 0.15)
				(type solid)
			)
			(layer "B.Fab")
		)
		(fp_line
			(start -0.652 -0.423)
			(end -0.652 0.425)
			(stroke
				(width 0.15)
				(type solid)
			)
			(layer "B.Fab")
		)
		(fp_line
			(start -0.35 0.4)
			(end -0.35 -0.4)
			(stroke
				(width 0.15)
				(type solid)
			)
			(layer "B.Fab")
		)
		(fp_line
			(start 0.65 0.425)
			(end 0.65 -0.423)
			(stroke
				(width 0.15)
				(type solid)
			)
			(layer "B.Fab")
		)
		(fp_line
			(start -0.652 0.425)
			(end 0.65 0.425)
			(stroke
				(width 0.15)
				(type solid)
			)
			(layer "B.Fab")
		)
		(fp_text user "License: Apache-2.0"
			(at -1.276 -5.9 90)
			(layer "B.Fab")
			(effects
				(font
					(size 0.7 0.7)
					(thickness 0.15)
				)
				(justify right top mirror)
			)
		)
		(fp_text user "Author: Antmicro"
			(at -1.276 -4.7 90)
			(layer "B.Fab")
			(effects
				(font
					(size 0.7 0.7)
					(thickness 0.15)
				)
				(justify right top mirror)
			)
		)
		(fp_text user "${REFERENCE}"
			(at -1.276 -3.499 90)
			(layer "B.Fab")
			(effects
				(font
					(size 0.7 0.7)
					(thickness 0.15)
				)
				(justify right top mirror)
			)
		)
		(pad "1" smd roundrect
			(at -0.701 0 90)
			(size 0.5 0.6)
			(layers "B.Cu" "B.Mask" "B.Paste")
			(roundrect_rratio 0.25)
			(net 1241 "Net-(D60-C)")
			(pinfunction "C")
			(pintype "passive")
		)
		(pad "2" smd roundrect
			(at 0.699 0 90)
			(size 0.5 0.6)
			(layers "B.Cu" "B.Mask" "B.Paste")
			(roundrect_rratio 0.25)
			(net 1240 "Net-(D60-A)")
			(pinfunction "A")
			(pintype "passive")
		)
	)
	(footprint "antmicro-footprints:R_1206_3216Metric"
		(layer "B.Cu")
		(at 92 66.1)
		(property "Reference" "R102"
			(at 1.9 2.2 180)
			(layer "B.SilkS")
			(effects
				(font
					(size 0.7 0.7)
					(thickness 0.15)
				)
				(justify left bottom mirror)
			)
		)
		(property "Value" "R_220R_1206"
			(at -2.422356 -2.103591 180)
			(layer "B.Fab")
			(effects
				(font
					(size 0.7 0.7)
					(thickness 0.15)
				)
				(justify left bottom mirror)
			)
		)
		(property "Datasheet" "https://www.bourns.com/docs/product-datasheets/cr.pdf"
			(at 0 0 180)
			(layer "B.Fab")
			(hide yes)
			(effects
				(font
					(size 1.27 1.27)
					(thickness 0.15)
				)
				(justify mirror)
			)
		)
		(property "Description" "SMT Chip Resistor, 220 ohm, ± 1%, 250 mW, 1206 [3216 Metric]"
			(at 0 0 180)
			(layer "B.Fab")
			(hide yes)
			(effects
				(font
					(size 1.27 1.27)
					(thickness 0.15)
				)
				(justify mirror)
			)
		)
		(property "MPN" "CR1206-FX-2200ELF"
			(at 0 0 180)
			(unlocked yes)
			(layer "B.Fab")
			(hide yes)
			(effects
				(font
					(size 1 1)
					(thickness 0.15)
				)
				(justify mirror)
			)
		)
		(property "Manufacturer" "Bourns"
			(at 0 0 180)
			(unlocked yes)
			(layer "B.Fab")
			(hide yes)
			(effects
				(font
					(size 1 1)
					(thickness 0.15)
				)
				(justify mirror)
			)
		)
		(property "License" "Apache-2.0"
			(at 0 0 180)
			(unlocked yes)
			(layer "B.Fab")
			(hide yes)
			(effects
				(font
					(size 1 1)
					(thickness 0.15)
				)
				(justify mirror)
			)
		)
		(property "Author" "Antmicro"
			(at 0 0 180)
			(unlocked yes)
			(layer "B.Fab")
			(hide yes)
			(effects
				(font
					(size 1 1)
					(thickness 0.15)
				)
				(justify mirror)
			)
		)
		(property "Val" "220R"
			(at 0 0 180)
			(unlocked yes)
			(layer "B.Fab")
			(hide yes)
			(effects
				(font
					(size 1 1)
					(thickness 0.15)
				)
				(justify mirror)
			)
		)
		(property "Tolerance" "1%"
			(at 0 0 180)
			(unlocked yes)
			(layer "B.Fab")
			(hide yes)
			(effects
				(font
					(size 1 1)
					(thickness 0.15)
				)
				(justify mirror)
			)
		)
		(sheetname "/SoM_Power/")
		(sheetfile "som_power.kicad_sch")
		(attr smd)
		(fp_line
			(start 0.8 -0.901)
			(end -0.8 -0.901)
			(stroke
				(width 0.15)
				(type solid)
			)
			(layer "B.SilkS")
		)
		(fp_line
			(start 0.8 0.899)
			(end -0.8 0.899)
			(stroke
				(width 0.15)
				(type solid)
			)
			(layer "B.SilkS")
		)
		(fp_rect
			(start -2.325 1.15)
			(end 2.325 -1.15)
			(stroke
				(width 0.05)
				(type default)
			)
			(fill no)
			(layer "B.CrtYd")
		)
		(fp_line
			(start -1.601 -0.8)
			(end 1.6 -0.8)
			(stroke
				(width 0.15)
				(type solid)
			)
			(layer "B.Fab")
		)
		(fp_line
			(start -1.601 0.802)
			(end -1.601 -0.8)
			(stroke
				(width 0.15)
				(type solid)
			)
			(layer "B.Fab")
		)
		(fp_line
			(start -1.601 0.802)
			(end 1.6 0.802)
			(stroke
				(width 0.15)
				(type solid)
			)
			(layer "B.Fab")
		)
		(fp_line
			(start 1.6 0.802)
			(end 1.6 -0.8)
			(stroke
				(width 0.15)
				(type solid)
			)
			(layer "B.Fab")
		)
		(fp_text user "Author: Antmicro"
			(at -2.401 -4.899 180)
			(layer "B.Fab")
			(effects
				(font
					(size 0.7 0.7)
					(thickness 0.15)
				)
				(justify left bottom mirror)
			)
		)
		(fp_text user "${REFERENCE}"
			(at -2.401 -3.5 180)
			(layer "B.Fab")
			(effects
				(font
					(size 0.7 0.7)
					(thickness 0.15)
				)
				(justify left bottom mirror)
			)
		)
		(fp_text user "License: Apache-2.0"
			(at -2.401 -6.3 180)
			(layer "B.Fab")
			(effects
				(font
					(size 0.7 0.7)
					(thickness 0.15)
				)
				(justify left bottom mirror)
			)
		)
		(pad "1" smd roundrect
			(at -1.5 -0.001)
			(size 1.15 1.8)
			(layers "B.Cu" "B.Mask" "B.Paste")
			(roundrect_rratio 0.25)
			(net 884 "Net-(Q8-D)")
			(pintype "passive")
		)
		(pad "2" smd roundrect
			(at 1.5 -0.001)
			(size 1.15 1.8)
			(layers "B.Cu" "B.Mask" "B.Paste")
			(roundrect_rratio 0.25)
			(net 12 "SYS_VIN_HV")
			(pintype "passive")
		)
	)
	(footprint "antmicro-footprints:TP_SMD_0.75mm"
		(layer "B.Cu")
		(at 174.14 58 180)
		(property "Reference" "TP131"
			(at -0.43 4.04 270)
			(layer "B.SilkS")
			(effects
				(font
					(size 0.7 0.7)
					(thickness 0.15)
				)
				(justify left bottom mirror)
			)
		)
		(property "Value" "TP_0.75mm_SMD"
			(at 0 -1.2 0)
			(layer "B.Fab")
			(effects
				(font
					(size 0.7 0.7)
					(thickness 0.15)
				)
				(justify left bottom mirror)
			)
		)
		(property "Description" "SMT test point"
			(at 0 0 0)
			(layer "B.Fab")
			(hide yes)
			(effects
				(font
					(size 1.27 1.27)
					(thickness 0.15)
				)
				(justify mirror)
			)
		)
		(property "MPN" ""
			(at 0 0 0)
			(unlocked yes)
			(layer "B.Fab")
			(hide yes)
			(effects
				(font
					(size 1 1)
					(thickness 0.15)
				)
				(justify mirror)
			)
		)
		(property "Manufacturer" ""
			(at 0 0 0)
			(unlocked yes)
			(layer "B.Fab")
			(hide yes)
			(effects
				(font
					(size 1 1)
					(thickness 0.15)
				)
				(justify mirror)
			)
		)
		(property "Author" "Antmicro"
			(at 0 0 0)
			(unlocked yes)
			(layer "B.Fab")
			(hide yes)
			(effects
				(font
					(size 1 1)
					(thickness 0.15)
				)
				(justify mirror)
			)
		)
		(property "License" "Apache-2.0"
			(at 0 0 0)
			(unlocked yes)
			(layer "B.Fab")
			(hide yes)
			(effects
				(font
					(size 1 1)
					(thickness 0.15)
				)
				(justify mirror)
			)
		)
		(sheetname "/Power/")
		(sheetfile "power.kicad_sch")
		(attr exclude_from_pos_files exclude_from_bom)
		(fp_circle
			(center 0 0)
			(end 0.475 0)
			(stroke
				(width 0.05)
				(type default)
			)
			(fill no)
			(layer "B.CrtYd")
		)
		(fp_text user "License: Apache-2.0"
			(at -0.4 -5.101 0)
			(layer "B.Fab")
			(effects
				(font
					(size 0.7 0.7)
					(thickness 0.15)
				)
				(justify left bottom mirror)
			)
		)
		(fp_text user "${REFERENCE}"
			(at -0.4 -2.7 0)
			(layer "B.Fab")
			(effects
				(font
					(size 0.7 0.7)
					(thickness 0.15)
				)
				(justify left bottom mirror)
			)
		)
		(fp_text user "Author: Antmicro"
			(at -0.4 -3.901 0)
			(layer "B.Fab")
			(effects
				(font
					(size 0.7 0.7)
					(thickness 0.15)
				)
				(justify left bottom mirror)
			)
		)
		(pad "1" smd circle
			(at 0 0 180)
			(size 0.75 0.75)
			(layers "B.Cu" "B.Mask")
			(net 491 "+5V_AON")
			(pinfunction "1")
			(pintype "passive")
		)
	)
)
